(kicad_pcb
	(version 20260206)
	(generator "pcbnew")
	(generator_version "10.0")
	(general
		(thickness 1.6)
		(legacy_teardrops no)
	)
	(paper "A4")
	(title_block
		(title "01162023_DA0F0TEBIF0_F0T_Expander_BD_F_brd_V02_OCP.brd")
		(comment 1 "Grand Teton / footprints 6727-6733 of 9728")
	)
	(layers
		(0 "F.Cu" signal "TOP")
		(4 "In1.Cu" signal "GND")
		(6 "In2.Cu" signal "VCC")
		(8 "In3.Cu" signal "VCC1")
		(10 "In4.Cu" signal "GND1")
		(12 "In5.Cu" signal "IN1")
		(14 "In6.Cu" signal "GND2")
		(16 "In7.Cu" signal "IN2")
		(18 "In8.Cu" signal "GND3")
		(20 "In9.Cu" signal "IN3")
		(22 "In10.Cu" signal "GND4")
		(24 "In11.Cu" signal "IN4")
		(26 "In12.Cu" signal "GND5")
		(28 "In13.Cu" signal "IN5")
		(30 "In14.Cu" signal "GND6")
		(32 "In15.Cu" signal "IN6")
		(34 "In16.Cu" signal "GND7")
		(2 "B.Cu" signal "BOTTOM")
		(9 "F.Adhes" user "F.Adhesive")
		(11 "B.Adhes" user "B.Adhesive")
		(13 "F.Paste" user "Package Geometry/Pastemask Top")
		(15 "B.Paste" user "Package Geometry/Pastemask Bottom")
		(5 "F.SilkS" user "Ref Des/Silkscreen Top")
		(7 "B.SilkS" user "Ref Des/Silkscreen Bottom")
		(1 "F.Mask" user "Board Geometry/Soldermask Top")
		(3 "B.Mask" user "Board Geometry/Soldermask Bottom")
		(17 "Dwgs.User" user "User.Drawings")
		(19 "Cmts.User" user "User.Comments")
		(21 "Eco1.User" user "User.Eco1")
		(23 "Eco2.User" user "User.Eco2")
		(25 "Edge.Cuts" user "Board Geometry/Outline")
		(27 "Margin" user)
		(31 "F.CrtYd" user "Package Geometry/Place Bound Top")
		(29 "B.CrtYd" user "Package Geometry/Place Bound Bottom")
		(35 "F.Fab" user "Ref Des/Assembly Top")
		(33 "B.Fab" user "Ref Des/Assembly Bottom")
	)
	(footprint ""
		(layer "F.Cu")
		(at 58.0644 -141.6558 180)
		(property "Reference" "R35"
			(at 0 0 180)
			(layer "F.SilkS")
			(hide yes)
			(effects
				(font
					(size 1.27 1.27)
				)
			)
		)
		(property "Value" ""
			(at 0 0 180)
			(layer "F.Fab")
			(effects
				(font
					(size 1.27 1.27)
				)
			)
		)
		(duplicate_pad_numbers_are_jumpers no)
		(fp_line
			(start 0.7874 0.4064)
			(end -0.7874 0.4064)
			(stroke
				(width 0.1524)
				(type default)
			)
			(layer "F.SilkS")
		)
		(fp_line
			(start 0.7874 -0.4064)
			(end 0.7874 0.4064)
			(stroke
				(width 0.1524)
				(type default)
			)
			(layer "F.SilkS")
		)
		(fp_line
			(start -0.7874 0.4064)
			(end -0.7874 -0.4064)
			(stroke
				(width 0.1524)
				(type default)
			)
			(layer "F.SilkS")
		)
		(fp_line
			(start -0.7874 -0.4064)
			(end 0.7874 -0.4064)
			(stroke
				(width 0.1524)
				(type default)
			)
			(layer "F.SilkS")
		)
		(fp_line
			(start 0.67945 0.3048)
			(end 0.120396 0.3048)
			(stroke
				(width 0.1)
				(type default)
			)
			(layer "F.Fab")
		)
		(fp_line
			(start 0.67945 -0.3048)
			(end 0.67945 0.3048)
			(stroke
				(width 0.1)
				(type default)
			)
			(layer "F.Fab")
		)
		(fp_line
			(start 0.12065 -0.2794)
			(end 0.12065 -0.3048)
			(stroke
				(width 0.1)
				(type default)
			)
			(layer "F.Fab")
		)
		(fp_line
			(start 0.12065 -0.3048)
			(end 0.67945 -0.3048)
			(stroke
				(width 0.1)
				(type default)
			)
			(layer "F.Fab")
		)
		(fp_line
			(start 0.120396 0.3048)
			(end 0.120396 0.2794)
			(stroke
				(width 0.1)
				(type default)
			)
			(layer "F.Fab")
		)
		(fp_line
			(start 0.120396 0.2794)
			(end -0.12065 0.2794)
			(stroke
				(width 0.1)
				(type default)
			)
			(layer "F.Fab")
		)
		(fp_line
			(start -0.12065 0.3048)
			(end -0.67945 0.3048)
			(stroke
				(width 0.1)
				(type default)
			)
			(layer "F.Fab")
		)
		(fp_line
			(start -0.12065 0.2794)
			(end -0.12065 0.3048)
			(stroke
				(width 0.1)
				(type default)
			)
			(layer "F.Fab")
		)
		(fp_line
			(start -0.12065 -0.2794)
			(end 0.12065 -0.2794)
			(stroke
				(width 0.1)
				(type default)
			)
			(layer "F.Fab")
		)
		(fp_line
			(start -0.12065 -0.305054)
			(end -0.12065 -0.2794)
			(stroke
				(width 0.1)
				(type default)
			)
			(layer "F.Fab")
		)
		(fp_line
			(start -0.67945 0.3048)
			(end -0.67945 -0.305054)
			(stroke
				(width 0.1)
				(type default)
			)
			(layer "F.Fab")
		)
		(fp_line
			(start -0.67945 -0.305054)
			(end -0.12065 -0.305054)
			(stroke
				(width 0.1)
				(type default)
			)
			(layer "F.Fab")
		)
		(pad "1" smd circle
			(at -0.40005 0 180)
			(size 0 0)
			(layers "F.Cu" "F.Mask" "F.Paste")
			(net "RST_SMB_NIC0_MUX_ISO_N")
		)
		(pad "2" smd circle
			(at 0.40005 0 180)
			(size 0 0)
			(layers "F.Cu" "F.Mask" "F.Paste")
			(net "P3V3_NIC0")
		)
	)
	(footprint ""
		(layer "F.Cu")
		(at 380.48946 -356.244906 90)
		(property "Reference" "C788"
			(at 0 0 90)
			(layer "F.SilkS")
			(hide yes)
			(effects
				(font
					(size 1.27 1.27)
				)
			)
		)
		(property "Value" ""
			(at 0 0 90)
			(layer "F.Fab")
			(effects
				(font
					(size 1.27 1.27)
				)
			)
		)
		(duplicate_pad_numbers_are_jumpers no)
		(fp_line
			(start 0.299974 -0.150114)
			(end 0.299974 0.150114)
			(stroke
				(width 0.1)
				(type default)
			)
			(layer "F.Fab")
		)
		(fp_line
			(start -0.299974 -0.150114)
			(end 0.299974 -0.150114)
			(stroke
				(width 0.1)
				(type default)
			)
			(layer "F.Fab")
		)
		(fp_line
			(start 0.299974 0.150114)
			(end -0.299974 0.150114)
			(stroke
				(width 0.1)
				(type default)
			)
			(layer "F.Fab")
		)
		(fp_line
			(start -0.299974 0.150114)
			(end -0.299974 -0.150114)
			(stroke
				(width 0.1)
				(type default)
			)
			(layer "F.Fab")
		)
		(pad "1" smd rect
			(at -0.2667 0 90)
			(size 0.3048 0.381)
			(layers "F.Cu" "F.Mask" "F.Paste")
			(net "P5E_PEX3_STN6_TX_DP<98>")
		)
		(pad "2" smd rect
			(at 0.2667 0 90)
			(size 0.3048 0.381)
			(layers "F.Cu" "F.Mask" "F.Paste")
			(net "P5E_PEX3_STN6_TX_C_DP<98>")
		)
	)
	(footprint ""
		(layer "F.Cu")
		(at 140.074142 -178.945286 180)
		(property "Reference" "R1103"
			(at 0 0 180)
			(layer "F.SilkS")
			(hide yes)
			(effects
				(font
					(size 1.27 1.27)
				)
			)
		)
		(property "Value" ""
			(at 0 0 180)
			(layer "F.Fab")
			(effects
				(font
					(size 1.27 1.27)
				)
			)
		)
		(duplicate_pad_numbers_are_jumpers no)
		(fp_line
			(start 0.7874 0.4064)
			(end -0.7874 0.4064)
			(stroke
				(width 0.1524)
				(type default)
			)
			(layer "F.SilkS")
		)
		(fp_line
			(start 0.67945 0.3048)
			(end 0.120396 0.3048)
			(stroke
				(width 0.1)
				(type default)
			)
			(layer "F.Fab")
		)
		(fp_line
			(start 0.67945 -0.3048)
			(end 0.67945 0.3048)
			(stroke
				(width 0.1)
				(type default)
			)
			(layer "F.Fab")
		)
		(fp_line
			(start 0.12065 -0.2794)
			(end 0.12065 -0.3048)
			(stroke
				(width 0.1)
				(type default)
			)
			(layer "F.Fab")
		)
		(fp_line
			(start 0.12065 -0.3048)
			(end 0.67945 -0.3048)
			(stroke
				(width 0.1)
				(type default)
			)
			(layer "F.Fab")
		)
		(fp_line
			(start 0.120396 0.3048)
			(end 0.120396 0.2794)
			(stroke
				(width 0.1)
				(type default)
			)
			(layer "F.Fab")
		)
		(fp_line
			(start 0.120396 0.2794)
			(end -0.12065 0.2794)
			(stroke
				(width 0.1)
				(type default)
			)
			(layer "F.Fab")
		)
		(fp_line
			(start -0.12065 0.3048)
			(end -0.67945 0.3048)
			(stroke
				(width 0.1)
				(type default)
			)
			(layer "F.Fab")
		)
		(fp_line
			(start -0.12065 0.2794)
			(end -0.12065 0.3048)
			(stroke
				(width 0.1)
				(type default)
			)
			(layer "F.Fab")
		)
		(fp_line
			(start -0.12065 -0.2794)
			(end 0.12065 -0.2794)
			(stroke
				(width 0.1)
				(type default)
			)
			(layer "F.Fab")
		)
		(fp_line
			(start -0.12065 -0.305054)
			(end -0.12065 -0.2794)
			(stroke
				(width 0.1)
				(type default)
			)
			(layer "F.Fab")
		)
		(fp_line
			(start -0.67945 0.3048)
			(end -0.67945 -0.305054)
			(stroke
				(width 0.1)
				(type default)
			)
			(layer "F.Fab")
		)
		(fp_line
			(start -0.67945 -0.305054)
			(end -0.12065 -0.305054)
			(stroke
				(width 0.1)
				(type default)
			)
			(layer "F.Fab")
		)
		(pad "1" smd circle
			(at -0.40005 0 180)
			(size 0 0)
			(layers "F.Cu" "F.Mask" "F.Paste")
			(net "CLK_100M_DB2000QL_NIC4_R_DN")
		)
		(pad "2" smd circle
			(at 0.40005 0 180)
			(size 0 0)
			(layers "F.Cu" "F.Mask" "F.Paste")
			(net "CLK_100M_DB2000QL_NIC4_DN")
		)
	)
	(footprint ""
		(layer "F.Cu")
		(at 340.458044 -356.244906 90)
		(property "Reference" "C521"
			(at 0 0 90)
			(layer "F.SilkS")
			(hide yes)
			(effects
				(font
					(size 1.27 1.27)
				)
			)
		)
		(property "Value" ""
			(at 0 0 90)
			(layer "F.Fab")
			(effects
				(font
					(size 1.27 1.27)
				)
			)
		)
		(duplicate_pad_numbers_are_jumpers no)
		(fp_line
			(start 0.299974 -0.150114)
			(end 0.299974 0.150114)
			(stroke
				(width 0.1)
				(type default)
			)
			(layer "F.Fab")
		)
		(fp_line
			(start -0.299974 -0.150114)
			(end 0.299974 -0.150114)
			(stroke
				(width 0.1)
				(type default)
			)
			(layer "F.Fab")
		)
		(fp_line
			(start 0.299974 0.150114)
			(end -0.299974 0.150114)
			(stroke
				(width 0.1)
				(type default)
			)
			(layer "F.Fab")
		)
		(fp_line
			(start -0.299974 0.150114)
			(end -0.299974 -0.150114)
			(stroke
				(width 0.1)
				(type default)
			)
			(layer "F.Fab")
		)
		(pad "1" smd rect
			(at -0.2667 0 90)
			(size 0.3048 0.381)
			(layers "F.Cu" "F.Mask" "F.Paste")
			(net "P5E_PEX2_STN5_TX_DP<94>")
		)
		(pad "2" smd rect
			(at 0.2667 0 90)
			(size 0.3048 0.381)
			(layers "F.Cu" "F.Mask" "F.Paste")
			(net "P5E_PEX2_STN5_TX_C_DP<94>")
		)
	)
	(footprint ""
		(layer "F.Cu")
		(at 83.754214 -48.21809)
		(property "Reference" "PD66"
			(at -3.337814 2.24536 0)
			(unlocked yes)
			(layer "F.SilkS")
			(effects
				(font
					(size 0.7874 0.5842)
					(thickness 0.1524)
				)
				(justify left)
			)
		)
		(property "Value" ""
			(at 0 0 0)
			(layer "F.Fab")
			(effects
				(font
					(size 1.27 1.27)
				)
			)
		)
		(duplicate_pad_numbers_are_jumpers no)
		(fp_line
			(start -3.400044 -1.459992)
			(end 4.107942 -1.459992)
			(stroke
				(width 0.1524)
				(type default)
			)
			(layer "F.SilkS")
		)
		(fp_line
			(start -3.400044 1.459992)
			(end -3.400044 -1.459992)
			(stroke
				(width 0.1524)
				(type default)
			)
			(layer "F.SilkS")
		)
		(fp_line
			(start 4.107942 -1.459992)
			(end 4.107942 1.459992)
			(stroke
				(width 0.1524)
				(type default)
			)
			(layer "F.SilkS")
		)
		(fp_line
			(start 4.107942 1.459992)
			(end -3.400044 1.459992)
			(stroke
				(width 0.1524)
				(type default)
			)
			(layer "F.SilkS")
		)
		(fp_poly
			(pts
				(xy 4.107942 -1.459992) (xy 4.107942 1.459992) (xy 3.308096 1.459992) (xy 3.308096 -1.459992)
			)
			(stroke
				(width 0)
				(type default)
			)
			(fill yes)
			(layer "F.SilkS")
		)
		(fp_line
			(start -2.29997 -1.459992)
			(end 2.29997 -1.459992)
			(stroke
				(width 0.1)
				(type default)
			)
			(layer "F.Fab")
		)
		(fp_line
			(start -2.29997 1.459992)
			(end -2.29997 -1.459992)
			(stroke
				(width 0.1)
				(type default)
			)
			(layer "F.Fab")
		)
		(fp_line
			(start 2.29997 -1.459992)
			(end 2.29997 1.459992)
			(stroke
				(width 0.1)
				(type default)
			)
			(layer "F.Fab")
		)
		(fp_line
			(start 2.29997 1.459992)
			(end -2.29997 1.459992)
			(stroke
				(width 0.1)
				(type default)
			)
			(layer "F.Fab")
		)
		(fp_text user "+"
			(at -4.7752 -0.12065 0)
			(unlocked yes)
			(layer "F.SilkS")
			(effects
				(font
					(size 1.905 1.4224)
					(thickness 0.1524)
				)
				(justify left)
			)
		)
		(fp_text user "-"
			(at 5.4102 0.29845 180)
			(unlocked yes)
			(layer "F.SilkS")
			(effects
				(font
					(size 1.905 1.4224)
					(thickness 0.1524)
				)
				(justify left)
			)
		)
		(fp_text user "+"
			(at -4.7752 -0.12065 0)
			(unlocked yes)
			(layer "F.Fab")
			(effects
				(font
					(size 1.905 1.4224)
					(thickness 0.1524)
				)
				(justify left)
			)
		)
		(fp_text user "-"
			(at 5.4102 0.29845 180)
			(unlocked yes)
			(layer "F.Fab")
			(effects
				(font
					(size 1.905 1.4224)
					(thickness 0.1524)
				)
				(justify left)
			)
		)
		(pad "A" smd rect
			(at -1.999996 0 90)
			(size 1.7018 2.5146)
			(layers "F.Cu" "F.Mask" "F.Paste")
			(net "GND")
		)
		(pad "C" smd rect
			(at 1.999996 0 90)
			(size 1.7018 2.5146)
			(layers "F.Cu" "F.Mask" "F.Paste")
			(net "P3V3_SSD3")
		)
	)
	(footprint ""
		(layer "F.Cu")
		(at 206.033116 -311.946544 135)
		(property "Reference" "R1302"
			(at 0 0 135)
			(layer "F.SilkS")
			(hide yes)
			(effects
				(font
					(size 1.27 1.27)
				)
			)
		)
		(property "Value" ""
			(at 0 0 135)
			(layer "F.Fab")
			(effects
				(font
					(size 1.27 1.27)
				)
			)
		)
		(duplicate_pad_numbers_are_jumpers no)
		(fp_line
			(start 0.787389 -0.406267)
			(end 0.787389 0.406267)
			(stroke
				(width 0.1524)
				(type default)
			)
			(layer "F.SilkS")
		)
		(fp_line
			(start 0.787389 0.406267)
			(end -0.787389 0.406267)
			(stroke
				(width 0.1524)
				(type default)
			)
			(layer "F.SilkS")
		)
		(fp_line
			(start -0.787389 -0.406267)
			(end 0.787389 -0.406267)
			(stroke
				(width 0.1524)
				(type default)
			)
			(layer "F.SilkS")
		)
		(fp_line
			(start -0.787389 0.406267)
			(end -0.787389 -0.406267)
			(stroke
				(width 0.1524)
				(type default)
			)
			(layer "F.SilkS")
		)
		(fp_line
			(start 0.679446 -0.30479)
			(end 0.679446 0.30479)
			(stroke
				(width 0.1)
				(type default)
			)
			(layer "F.Fab")
		)
		(fp_line
			(start 0.120515 -0.30479)
			(end 0.679446 -0.30479)
			(stroke
				(width 0.1)
				(type default)
			)
			(layer "F.Fab")
		)
		(fp_line
			(start 0.120695 -0.279466)
			(end 0.120515 -0.30479)
			(stroke
				(width 0.1)
				(type default)
			)
			(layer "F.Fab")
		)
		(fp_line
			(start 0.679446 0.30479)
			(end 0.120515 0.30479)
			(stroke
				(width 0.1)
				(type default)
			)
			(layer "F.Fab")
		)
		(fp_line
			(start -0.120695 -0.304969)
			(end -0.120695 -0.279466)
			(stroke
				(width 0.1)
				(type default)
			)
			(layer "F.Fab")
		)
		(fp_line
			(start -0.120695 -0.279466)
			(end 0.120695 -0.279466)
			(stroke
				(width 0.1)
				(type default)
			)
			(layer "F.Fab")
		)
		(fp_line
			(start 0.120335 0.279466)
			(end -0.120695 0.279466)
			(stroke
				(width 0.1)
				(type default)
			)
			(layer "F.Fab")
		)
		(fp_line
			(start 0.120515 0.30479)
			(end 0.120335 0.279466)
			(stroke
				(width 0.1)
				(type default)
			)
			(layer "F.Fab")
		)
		(fp_line
			(start -0.679446 -0.305149)
			(end -0.120695 -0.304969)
			(stroke
				(width 0.1)
				(type default)
			)
			(layer "F.Fab")
		)
		(fp_line
			(start -0.120695 0.279466)
			(end -0.120515 0.30479)
			(stroke
				(width 0.1)
				(type default)
			)
			(layer "F.Fab")
		)
		(fp_line
			(start -0.120515 0.30479)
			(end -0.679446 0.30479)
			(stroke
				(width 0.1)
				(type default)
			)
			(layer "F.Fab")
		)
		(fp_line
			(start -0.679446 0.30479)
			(end -0.679446 -0.305149)
			(stroke
				(width 0.1)
				(type default)
			)
			(layer "F.Fab")
		)
		(pad "1" smd circle
			(at -0.40005 0 135)
			(size 0 0)
			(layers "F.Cu" "F.Mask" "F.Paste")
			(net "PEX1_SPARE5")
		)
		(pad "2" smd circle
			(at 0.40005 0 135)
			(size 0 0)
			(layers "F.Cu" "F.Mask" "F.Paste")
			(net "P1V8_PEX")
		)
	)
	(footprint ""
		(layer "F.Cu")
		(at 251.698506 -66.32194 -90)
		(property "Reference" "PC865"
			(at 0 0 270)
			(layer "F.SilkS")
			(hide yes)
			(effects
				(font
					(size 1.27 1.27)
				)
			)
		)
		(property "Value" ""
			(at 0 0 270)
			(layer "F.Fab")
			(effects
				(font
					(size 1.27 1.27)
				)
			)
		)
		(duplicate_pad_numbers_are_jumpers no)
		(fp_line
			(start -0.7874 0.4064)
			(end -0.7874 -0.4064)
			(stroke
				(width 0.1524)
				(type default)
			)
			(layer "F.SilkS")
		)
		(fp_line
			(start 0.7874 0.4064)
			(end -0.7874 0.4064)
			(stroke
				(width 0.1524)
				(type default)
			)
			(layer "F.SilkS")
		)
		(fp_line
			(start -0.7874 -0.4064)
			(end 0.7874 -0.4064)
			(stroke
				(width 0.1524)
				(type default)
			)
			(layer "F.SilkS")
		)
		(fp_line
			(start 0.7874 -0.4064)
			(end 0.7874 0.4064)
			(stroke
				(width 0.1524)
				(type default)
			)
			(layer "F.SilkS")
		)
		(fp_line
			(start -0.67945 0.3048)
			(end -0.67945 -0.305054)
			(stroke
				(width 0.1)
				(type default)
			)
			(layer "F.Fab")
		)
		(fp_line
			(start -0.12065 0.3048)
			(end -0.67945 0.3048)
			(stroke
				(width 0.1)
				(type default)
			)
			(layer "F.Fab")
		)
		(fp_line
			(start 0.120396 0.3048)
			(end 0.120396 0.2794)
			(stroke
				(width 0.1)
				(type default)
			)
			(layer "F.Fab")
		)
		(fp_line
			(start 0.67945 0.3048)
			(end 0.120396 0.3048)
			(stroke
				(width 0.1)
				(type default)
			)
			(layer "F.Fab")
		)
		(fp_line
			(start -0.12065 0.2794)
			(end -0.12065 0.3048)
			(stroke
				(width 0.1)
				(type default)
			)
			(layer "F.Fab")
		)
		(fp_line
			(start 0.120396 0.2794)
			(end -0.12065 0.2794)
			(stroke
				(width 0.1)
				(type default)
			)
			(layer "F.Fab")
		)
		(fp_line
			(start -0.12065 -0.2794)
			(end 0.12065 -0.2794)
			(stroke
				(width 0.1)
				(type default)
			)
			(layer "F.Fab")
		)
		(fp_line
			(start 0.12065 -0.2794)
			(end 0.12065 -0.3048)
			(stroke
				(width 0.1)
				(type default)
			)
			(layer "F.Fab")
		)
		(fp_line
			(start 0.12065 -0.3048)
			(end 0.67945 -0.3048)
			(stroke
				(width 0.1)
				(type default)
			)
			(layer "F.Fab")
		)
		(fp_line
			(start 0.67945 -0.3048)
			(end 0.67945 0.3048)
			(stroke
				(width 0.1)
				(type default)
			)
			(layer "F.Fab")
		)
		(fp_line
			(start -0.67945 -0.305054)
			(end -0.12065 -0.305054)
			(stroke
				(width 0.1)
				(type default)
			)
			(layer "F.Fab")
		)
		(fp_line
			(start -0.12065 -0.305054)
			(end -0.12065 -0.2794)
			(stroke
				(width 0.1)
				(type default)
			)
			(layer "F.Fab")
		)
		(pad "1" smd circle
			(at -0.40005 0 270)
			(size 0 0)
			(layers "F.Cu" "F.Mask" "F.Paste")
			(net "P12V_SSD8_CO_GATE")
		)
		(pad "2" smd circle
			(at 0.40005 0 270)
			(size 0 0)
			(layers "F.Cu" "F.Mask" "F.Paste")
			(net "GND")
		)
	)
)
